# T6G (Grand Teton) — schematic netlist excerpt (pin names and nets, part order shuffled) for the footprints in the layout excerpt that follows; sources: Cadence DE-HDL packaged netlist, KiCad conversion of 04192023_DAF0TMB3IC0_F0TG_MB_C_brd_V02_OCP.brd

R3783  Q_RES  100K 1% EMPTY  pkg 0402LF  page 134 : A = P3V3_AUX ; B = OCP_V3_1_P3V3_PWRGD
C965  Q_CAP_DIFFBUS  DIFF BUS_0.22UF 6.3V 20% X6S  pkg C0201  page 63 : \1\ = P5E_CPU0_P1_TX_C_DP<0> ; \2\ = P5E_CPU0_P1_TX_DP<0>
R2529  Q_RES  0 5% CHIP  pkg 0402LF  page 242 : A = FM_P12V_HSC_EN_N ; B = FM_P12V_HSC_EN_R_N

(kicad_pcb
	(version 20260206)
	(generator "pcbnew")
	(generator_version "10.0")
	(general
		(thickness 1.6)
		(legacy_teardrops no)
	)
	(paper "A4")
	(title_block
		(title "04192023_DAF0TMB3IC0_F0TG_MB_C_brd_V02_OCP.brd")
		(comment 1 "Grand Teton / footprints 3745-3747 of 8354")
	)
	(layers
		(0 "F.Cu" signal "TOP")
		(4 "In1.Cu" signal "GND")
		(6 "In2.Cu" signal "IN1")
		(8 "In3.Cu" signal "GND1")
		(10 "In4.Cu" signal "IN2")
		(12 "In5.Cu" signal "GND2")
		(14 "In6.Cu" signal "IN3")
		(16 "In7.Cu" signal "GND3")
		(18 "In8.Cu" signal "VCC")
		(20 "In9.Cu" signal "VCC1")
		(22 "In10.Cu" signal "GND4")
		(24 "In11.Cu" signal "IN4")
		(26 "In12.Cu" signal "GND5")
		(28 "In13.Cu" signal "IN5")
		(30 "In14.Cu" signal "GND6")
		(32 "In15.Cu" signal "IN6")
		(34 "In16.Cu" signal "GND7")
		(2 "B.Cu" signal "BOTTOM")
		(9 "F.Adhes" user "F.Adhesive")
		(11 "B.Adhes" user "B.Adhesive")
		(13 "F.Paste" user "Package Geometry/Pastemask Top")
		(15 "B.Paste" user "Package Geometry/Pastemask Bottom")
		(5 "F.SilkS" user "Ref Des/Silkscreen Top")
		(7 "B.SilkS" user "Ref Des/Silkscreen Bottom")
		(1 "F.Mask" user "Board Geometry/Soldermask Top")
		(3 "B.Mask" user "Board Geometry/Soldermask Bottom")
		(17 "Dwgs.User" user "User.Drawings")
		(19 "Cmts.User" user "User.Comments")
		(21 "Eco1.User" user "User.Eco1")
		(23 "Eco2.User" user "User.Eco2")
		(25 "Edge.Cuts" user "Board Geometry/Outline")
		(27 "Margin" user)
		(31 "F.CrtYd" user "Package Geometry/Place Bound Top")
		(29 "B.CrtYd" user "Package Geometry/Place Bound Bottom")
		(35 "F.Fab" user "Ref Des/Assembly Top")
		(33 "B.Fab" user "Ref Des/Assembly Bottom")
	)
	(footprint ""
		(layer "F.Cu")
		(at 430.277016 -101.97719 180)
		(property "Reference" "R3783"
			(at 0 0 180)
			(layer "F.SilkS")
			(hide yes)
			(effects
				(font
					(size 1.27 1.27)
				)
			)
		)
		(property "Value" ""
			(at 0 0 180)
			(layer "F.Fab")
			(effects
				(font
					(size 1.27 1.27)
				)
			)
		)
		(duplicate_pad_numbers_are_jumpers no)
		(fp_line
			(start 0.7874 0.4064)
			(end -0.7874 0.4064)
			(stroke
				(width 0.1524)
				(type default)
			)
			(layer "F.SilkS")
		)
		(fp_line
			(start 0.7874 -0.4064)
			(end 0.7874 0.4064)
			(stroke
				(width 0.1524)
				(type default)
			)
			(layer "F.SilkS")
		)
		(fp_line
			(start -0.7874 0.4064)
			(end -0.7874 -0.4064)
			(stroke
				(width 0.1524)
				(type default)
			)
			(layer "F.SilkS")
		)
		(fp_line
			(start -0.7874 -0.4064)
			(end 0.7874 -0.4064)
			(stroke
				(width 0.1524)
				(type default)
			)
			(layer "F.SilkS")
		)
		(fp_line
			(start 0.67945 0.3048)
			(end 0.120396 0.3048)
			(stroke
				(width 0.1)
				(type default)
			)
			(layer "F.Fab")
		)
		(fp_line
			(start 0.67945 -0.3048)
			(end 0.67945 0.3048)
			(stroke
				(width 0.1)
				(type default)
			)
			(layer "F.Fab")
		)
		(fp_line
			(start 0.12065 -0.2794)
			(end 0.12065 -0.3048)
			(stroke
				(width 0.1)
				(type default)
			)
			(layer "F.Fab")
		)
		(fp_line
			(start 0.12065 -0.3048)
			(end 0.67945 -0.3048)
			(stroke
				(width 0.1)
				(type default)
			)
			(layer "F.Fab")
		)
		(fp_line
			(start 0.120396 0.3048)
			(end 0.120396 0.2794)
			(stroke
				(width 0.1)
				(type default)
			)
			(layer "F.Fab")
		)
		(fp_line
			(start 0.120396 0.2794)
			(end -0.12065 0.2794)
			(stroke
				(width 0.1)
				(type default)
			)
			(layer "F.Fab")
		)
		(fp_line
			(start -0.12065 0.3048)
			(end -0.67945 0.3048)
			(stroke
				(width 0.1)
				(type default)
			)
			(layer "F.Fab")
		)
		(fp_line
			(start -0.12065 0.2794)
			(end -0.12065 0.3048)
			(stroke
				(width 0.1)
				(type default)
			)
			(layer "F.Fab")
		)
		(fp_line
			(start -0.12065 -0.2794)
			(end 0.12065 -0.2794)
			(stroke
				(width 0.1)
				(type default)
			)
			(layer "F.Fab")
		)
		(fp_line
			(start -0.12065 -0.305054)
			(end -0.12065 -0.2794)
			(stroke
				(width 0.1)
				(type default)
			)
			(layer "F.Fab")
		)
		(fp_line
			(start -0.67945 0.3048)
			(end -0.67945 -0.305054)
			(stroke
				(width 0.1)
				(type default)
			)
			(layer "F.Fab")
		)
		(fp_line
			(start -0.67945 -0.305054)
			(end -0.12065 -0.305054)
			(stroke
				(width 0.1)
				(type default)
			)
			(layer "F.Fab")
		)
		(pad "1" smd circle
			(at -0.40005 0 180)
			(size 0 0)
			(layers "F.Cu" "F.Mask" "F.Paste")
			(net "P3V3_AUX")
		)
		(pad "2" smd circle
			(at 0.40005 0 180)
			(size 0 0)
			(layers "F.Cu" "F.Mask" "F.Paste")
			(net "OCP_V3_1_P3V3_PWRGD")
		)
	)
	(footprint ""
		(layer "F.Cu")
		(at 331.494892 -390.77646 180)
		(property "Reference" "C965"
			(at 0 0 180)
			(layer "F.SilkS")
			(hide yes)
			(effects
				(font
					(size 1.27 1.27)
				)
			)
		)
		(property "Value" ""
			(at 0 0 180)
			(layer "F.Fab")
			(effects
				(font
					(size 1.27 1.27)
				)
			)
		)
		(duplicate_pad_numbers_are_jumpers no)
		(fp_line
			(start 0.299974 0.150114)
			(end -0.299974 0.150114)
			(stroke
				(width 0.1)
				(type default)
			)
			(layer "F.Fab")
		)
		(fp_line
			(start 0.299974 -0.150114)
			(end 0.299974 0.150114)
			(stroke
				(width 0.1)
				(type default)
			)
			(layer "F.Fab")
		)
		(fp_line
			(start -0.299974 0.150114)
			(end -0.299974 -0.150114)
			(stroke
				(width 0.1)
				(type default)
			)
			(layer "F.Fab")
		)
		(fp_line
			(start -0.299974 -0.150114)
			(end 0.299974 -0.150114)
			(stroke
				(width 0.1)
				(type default)
			)
			(layer "F.Fab")
		)
		(pad "1" smd rect
			(at -0.2667 0 180)
			(size 0.3048 0.381)
			(layers "F.Cu" "F.Mask" "F.Paste")
			(net "P5E_CPU0_P1_TX_C_DP<0>")
		)
		(pad "2" smd rect
			(at 0.2667 0 180)
			(size 0.3048 0.381)
			(layers "F.Cu" "F.Mask" "F.Paste")
			(net "P5E_CPU0_P1_TX_DP<0>")
		)
	)
	(footprint ""
		(layer "F.Cu")
		(at 205.693518 -143.112998 90)
		(property "Reference" "R2529"
			(at 0 0 90)
			(layer "F.SilkS")
			(hide yes)
			(effects
				(font
					(size 1.27 1.27)
				)
			)
		)
		(property "Value" ""
			(at 0 0 90)
			(layer "F.Fab")
			(effects
				(font
					(size 1.27 1.27)
				)
			)
		)
		(duplicate_pad_numbers_are_jumpers no)
		(fp_line
			(start 0.7874 -0.4064)
			(end 0.7874 0.4064)
			(stroke
				(width 0.1524)
				(type default)
			)
			(layer "F.SilkS")
		)
		(fp_line
			(start -0.7874 -0.4064)
			(end 0.7874 -0.4064)
			(stroke
				(width 0.1524)
				(type default)
			)
			(layer "F.SilkS")
		)
		(fp_line
			(start 0.7874 0.4064)
			(end -0.7874 0.4064)
			(stroke
				(width 0.1524)
				(type default)
			)
			(layer "F.SilkS")
		)
		(fp_line
			(start -0.7874 0.4064)
			(end -0.7874 -0.4064)
			(stroke
				(width 0.1524)
				(type default)
			)
			(layer "F.SilkS")
		)
		(fp_line
			(start -0.12065 -0.305054)
			(end -0.12065 -0.2794)
			(stroke
				(width 0.1)
				(type default)
			)
			(layer "F.Fab")
		)
		(fp_line
			(start -0.67945 -0.305054)
			(end -0.12065 -0.305054)
			(stroke
				(width 0.1)
				(type default)
			)
			(layer "F.Fab")
		)
		(fp_line
			(start 0.67945 -0.3048)
			(end 0.67945 0.3048)
			(stroke
				(width 0.1)
				(type default)
			)
			(layer "F.Fab")
		)
		(fp_line
			(start 0.12065 -0.3048)
			(end 0.67945 -0.3048)
			(stroke
				(width 0.1)
				(type default)
			)
			(layer "F.Fab")
		)
		(fp_line
			(start 0.12065 -0.2794)
			(end 0.12065 -0.3048)
			(stroke
				(width 0.1)
				(type default)
			)
			(layer "F.Fab")
		)
		(fp_line
			(start -0.12065 -0.2794)
			(end 0.12065 -0.2794)
			(stroke
				(width 0.1)
				(type default)
			)
			(layer "F.Fab")
		)
		(fp_line
			(start 0.120396 0.2794)
			(end -0.12065 0.2794)
			(stroke
				(width 0.1)
				(type default)
			)
			(layer "F.Fab")
		)
		(fp_line
			(start -0.12065 0.2794)
			(end -0.12065 0.3048)
			(stroke
				(width 0.1)
				(type default)
			)
			(layer "F.Fab")
		)
		(fp_line
			(start 0.67945 0.3048)
			(end 0.120396 0.3048)
			(stroke
				(width 0.1)
				(type default)
			)
			(layer "F.Fab")
		)
		(fp_line
			(start 0.120396 0.3048)
			(end 0.120396 0.2794)
			(stroke
				(width 0.1)
				(type default)
			)
			(layer "F.Fab")
		)
		(fp_line
			(start -0.12065 0.3048)
			(end -0.67945 0.3048)
			(stroke
				(width 0.1)
				(type default)
			)
			(layer "F.Fab")
		)
		(fp_line
			(start -0.67945 0.3048)
			(end -0.67945 -0.305054)
			(stroke
				(width 0.1)
				(type default)
			)
			(layer "F.Fab")
		)
		(pad "1" smd circle
			(at -0.40005 0 90)
			(size 0 0)
			(layers "F.Cu" "F.Mask" "F.Paste")
			(net "FM_P12V_HSC_EN_N")
		)
		(pad "2" smd circle
			(at 0.40005 0 90)
			(size 0 0)
			(layers "F.Cu" "F.Mask" "F.Paste")
			(net "FM_P12V_HSC_EN_R_N")
		)
	)
)
